# BASEBOARD_FAB2 (Tioga Pass) — schematic netlist excerpt (pin names and nets, part order shuffled) for the footprints in the layout excerpt that follows; sources: Cadence DE-HDL packaged netlist, KiCad conversion of Wiwynn_Tioga_Pass_MB.brd

R32W5  RES  2.0K 1% CHIP  pkg 0402  page 185 : A = P1V8_M2 ; B = SMB_M2_SCL
R2T61  RES  0.0 5% EMPTY  pkg 0402  page 93 : A = H_CPU_ERR1_PCH_N ; B = H_CPU_ERR1_GTL_R_N
C3N7  CAP_A  1.0UF 6.3V 10% X6S  pkg 0402V  page 132 : A = PVNN_PCH_STBY ; B = GND

(kicad_pcb
	(version 20260206)
	(generator "pcbnew")
	(generator_version "10.0")
	(general
		(thickness 1.6)
		(legacy_teardrops no)
	)
	(paper "A4")
	(title_block
		(title "Wiwynn_Tioga_Pass_MB.brd")
		(comment 1 "Tioga Pass / footprints 2763-2765 of 4770")
	)
	(layers
		(0 "F.Cu" signal "TOP")
		(4 "In1.Cu" signal "L2GND")
		(6 "In2.Cu" signal "L3")
		(8 "In3.Cu" signal "L4GND")
		(10 "In4.Cu" signal "L5")
		(12 "In5.Cu" signal "L6GND")
		(14 "In6.Cu" signal "L7VCC")
		(16 "In7.Cu" signal "L8VCC")
		(18 "In8.Cu" signal "L9GND")
		(20 "In9.Cu" signal "L10")
		(22 "In10.Cu" signal "L11GND")
		(24 "In11.Cu" signal "L12")
		(26 "In12.Cu" signal "L13GND")
		(2 "B.Cu" signal "BOTTOM")
		(9 "F.Adhes" user "F.Adhesive")
		(11 "B.Adhes" user "B.Adhesive")
		(13 "F.Paste" user "Package Geometry/Pastemask Top")
		(15 "B.Paste" user "Package Geometry/Pastemask Bottom")
		(5 "F.SilkS" user "Ref Des/Silkscreen Top")
		(7 "B.SilkS" user "Ref Des/Silkscreen Bottom")
		(1 "F.Mask" user "Board Geometry/Soldermask Top")
		(3 "B.Mask" user "Board Geometry/Soldermask Bottom")
		(17 "Dwgs.User" user "User.Drawings")
		(19 "Cmts.User" user "User.Comments")
		(21 "Eco1.User" user "User.Eco1")
		(23 "Eco2.User" user "User.Eco2")
		(25 "Edge.Cuts" user "Board Geometry/Outline")
		(27 "Margin" user)
		(31 "F.CrtYd" user "Package Geometry/Place Bound Top")
		(29 "B.CrtYd" user "Package Geometry/Place Bound Bottom")
		(35 "F.Fab" user "Ref Des/Assembly Top")
		(33 "B.Fab" user "Ref Des/Assembly Bottom")
	)
	(footprint ""
		(layer "B.Cu")
		(at 383.73685 -111.05515 -90)
		(property "Reference" "C3N7"
			(at 0 0 90)
			(layer "B.SilkS")
			(hide yes)
			(effects
				(font
					(size 1.27 1.27)
				)
				(justify mirror)
			)
		)
		(property "Value" ""
			(at 0 0 90)
			(layer "B.Fab")
			(effects
				(font
					(size 1.27 1.27)
				)
				(justify mirror)
			)
		)
		(duplicate_pad_numbers_are_jumpers no)
		(fp_rect
			(start 0.2794 0.9144)
			(end -0.2794 -0.1143)
			(stroke
				(width 0)
				(type default)
			)
			(fill no)
			(layer "B.CrtYd")
		)
		(fp_line
			(start -0.2794 0.9144)
			(end 0.2794 0.9144)
			(stroke
				(width 0.1)
				(type default)
			)
			(layer "B.Fab")
		)
		(fp_line
			(start 0.2794 0.9144)
			(end 0.2794 -0.1143)
			(stroke
				(width 0.1)
				(type default)
			)
			(layer "B.Fab")
		)
		(fp_line
			(start -0.2794 -0.1143)
			(end -0.2794 0.9144)
			(stroke
				(width 0.1)
				(type default)
			)
			(layer "B.Fab")
		)
		(fp_line
			(start 0.2794 -0.1143)
			(end -0.2794 -0.1143)
			(stroke
				(width 0.1)
				(type default)
			)
			(layer "B.Fab")
		)
		(pad "1" smd custom
			(at 0 0 180)
			(size 0.10414 0.10414)
			(layers "B.Cu" "B.Mask" "B.Paste")
			(net "PVNN_PCH_STBY")
			(options
				(clearance outline)
				(anchor circle)
			)
			(primitives
				(gr_poly
					(pts
						(xy -0.20828 -0.08636) (xy -0.20828 0.08636) (xy -0.08636 0.20828) (xy 0.086614 0.20828) (xy 0.20828 0.086614)
						(xy 0.20828 -0.08636) (xy 0.08636 -0.20828) (xy -0.08636 -0.20828)
					)
					(width 0)
					(fill yes)
				)
			)
		)
		(pad "2" smd custom
			(at 0 0.8001 180)
			(size 0.10414 0.10414)
			(layers "B.Cu" "B.Mask" "B.Paste")
			(net "GND")
			(options
				(clearance outline)
				(anchor circle)
			)
			(primitives
				(gr_poly
					(pts
						(xy -0.20828 -0.08636) (xy -0.20828 0.08636) (xy -0.08636 0.20828) (xy 0.086614 0.20828) (xy 0.20828 0.086614)
						(xy 0.20828 -0.08636) (xy 0.08636 -0.20828) (xy -0.08636 -0.20828)
					)
					(width 0)
					(fill yes)
				)
			)
		)
		(zone
			(layer "B.Cu")
			(hatch none 0.5)
			(connect_pads
				(clearance 0)
			)
			(min_thickness 0.25)
			(keepout
				(tracks allowed)
				(vias not_allowed)
				(pads allowed)
				(copperpour not_allowed)
				(footprints allowed)
			)
			(placement
				(enabled no)
				(sheetname "")
			)
			(fill
				(thermal_gap 0.5)
				(thermal_bridge_width 0.5)
				(island_removal_mode 0)
			)
			(polygon
				(pts
					(xy 383.5273 -110.96752) (xy 383.1463 -110.96752) (xy 383.1463 -111.14278) (xy 383.5273 -111.143034)
				)
			)
		)
		(zone
			(layer "B.Cu")
			(hatch none 0.5)
			(connect_pads
				(clearance 0)
			)
			(min_thickness 0.25)
			(keepout
				(tracks not_allowed)
				(vias allowed)
				(pads allowed)
				(copperpour not_allowed)
				(footprints allowed)
			)
			(placement
				(enabled no)
				(sheetname "")
			)
			(fill
				(thermal_gap 0.5)
				(thermal_bridge_width 0.5)
				(island_removal_mode 0)
			)
			(polygon
				(pts
					(xy 383.5273 -110.96752) (xy 383.1463 -110.96752) (xy 383.1463 -111.14278) (xy 383.5273 -111.143034)
				)
			)
		)
	)
	(footprint ""
		(layer "B.Cu")
		(at 376.170952 -43.224958)
		(property "Reference" "R2T61"
			(at 0 0 0)
			(layer "B.SilkS")
			(hide yes)
			(effects
				(font
					(size 1.27 1.27)
				)
				(justify mirror)
			)
		)
		(property "Value" ""
			(at 0 0 0)
			(layer "B.Fab")
			(effects
				(font
					(size 1.27 1.27)
				)
				(justify mirror)
			)
		)
		(duplicate_pad_numbers_are_jumpers no)
		(fp_poly
			(pts
				(xy 0.2794 -0.1016) (xy -0.2794 -0.1016) (xy -0.2794 0.9906) (xy 0.2794 0.9906)
			)
			(stroke
				(width 0)
				(type default)
			)
			(fill no)
			(layer "B.CrtYd")
		)
		(fp_line
			(start -0.2794 -0.1016)
			(end 0.2794 -0.1016)
			(stroke
				(width 0.1)
				(type default)
			)
			(layer "B.Fab")
		)
		(fp_line
			(start -0.2794 0.9906)
			(end -0.2794 -0.1016)
			(stroke
				(width 0.1)
				(type default)
			)
			(layer "B.Fab")
		)
		(fp_line
			(start 0.2794 -0.1016)
			(end 0.2794 0.9906)
			(stroke
				(width 0.1)
				(type default)
			)
			(layer "B.Fab")
		)
		(fp_line
			(start 0.2794 0.9906)
			(end -0.2794 0.9906)
			(stroke
				(width 0.1)
				(type default)
			)
			(layer "B.Fab")
		)
		(pad "1" smd rect
			(at 0 0 180)
			(size 0.508 0.508)
			(layers "B.Cu" "B.Mask" "B.Paste")
			(net "H_CPU_ERR1_PCH_N")
		)
		(pad "2" smd rect
			(at 0 0.889 180)
			(size 0.508 0.508)
			(layers "B.Cu" "B.Mask" "B.Paste")
			(net "H_CPU_ERR1_GTL_R_N")
		)
		(zone
			(layer "B.Cu")
			(hatch none 0.5)
			(connect_pads
				(clearance 0)
			)
			(min_thickness 0.25)
			(keepout
				(tracks allowed)
				(vias not_allowed)
				(pads allowed)
				(copperpour not_allowed)
				(footprints allowed)
			)
			(placement
				(enabled no)
				(sheetname "")
			)
			(fill
				(thermal_gap 0.5)
				(thermal_bridge_width 0.5)
				(island_removal_mode 0)
			)
			(polygon
				(pts
					(xy 376.424952 -42.970958) (xy 375.916952 -42.970958) (xy 375.916952 -42.589958) (xy 376.424952 -42.589958)
				)
			)
		)
		(zone
			(layer "B.Cu")
			(hatch none 0.5)
			(connect_pads
				(clearance 0)
			)
			(min_thickness 0.25)
			(keepout
				(tracks not_allowed)
				(vias allowed)
				(pads allowed)
				(copperpour not_allowed)
				(footprints allowed)
			)
			(placement
				(enabled no)
				(sheetname "")
			)
			(fill
				(thermal_gap 0.5)
				(thermal_bridge_width 0.5)
				(island_removal_mode 0)
			)
			(polygon
				(pts
					(xy 376.424952 -42.589958) (xy 375.916952 -42.589958) (xy 375.916952 -42.970958) (xy 376.424952 -42.970958)
				)
			)
		)
	)
	(footprint ""
		(layer "B.Cu")
		(at 396.978886 -16.438372 180)
		(property "Reference" "R32W5"
			(at 0.8382 -0.67818 180)
			(unlocked yes)
			(layer "B.SilkS")
			(effects
				(font
					(size 0.4064 0.254)
					(thickness 0.1524)
				)
				(justify left mirror)
			)
		)
		(property "Value" ""
			(at 0 0 0)
			(layer "B.Fab")
			(effects
				(font
					(size 1.27 1.27)
				)
				(justify mirror)
			)
		)
		(duplicate_pad_numbers_are_jumpers no)
		(fp_poly
			(pts
				(xy 0.2794 -0.1016) (xy -0.2794 -0.1016) (xy -0.2794 0.9906) (xy 0.2794 0.9906)
			)
			(stroke
				(width 0)
				(type default)
			)
			(fill no)
			(layer "B.CrtYd")
		)
		(fp_line
			(start 0.2794 0.9906)
			(end -0.2794 0.9906)
			(stroke
				(width 0.1)
				(type default)
			)
			(layer "B.Fab")
		)
		(fp_line
			(start 0.2794 -0.1016)
			(end 0.2794 0.9906)
			(stroke
				(width 0.1)
				(type default)
			)
			(layer "B.Fab")
		)
		(fp_line
			(start -0.2794 0.9906)
			(end -0.2794 -0.1016)
			(stroke
				(width 0.1)
				(type default)
			)
			(layer "B.Fab")
		)
		(fp_line
			(start -0.2794 -0.1016)
			(end 0.2794 -0.1016)
			(stroke
				(width 0.1)
				(type default)
			)
			(layer "B.Fab")
		)
		(pad "1" smd rect
			(at 0 0)
			(size 0.508 0.508)
			(layers "B.Cu" "B.Mask" "B.Paste")
			(net "P1V8_M2")
		)
		(pad "2" smd rect
			(at 0 0.889)
			(size 0.508 0.508)
			(layers "B.Cu" "B.Mask" "B.Paste")
			(net "SMB_M2_SCL")
		)
		(zone
			(layer "B.Cu")
			(hatch none 0.5)
			(connect_pads
				(clearance 0)
			)
			(min_thickness 0.25)
			(keepout
				(tracks not_allowed)
				(vias allowed)
				(pads allowed)
				(copperpour not_allowed)
				(footprints allowed)
			)
			(placement
				(enabled no)
				(sheetname "")
			)
			(fill
				(thermal_gap 0.5)
				(thermal_bridge_width 0.5)
				(island_removal_mode 0)
			)
			(polygon
				(pts
					(xy 396.724886 -17.073372) (xy 397.232886 -17.073372) (xy 397.232886 -16.692372) (xy 396.724886 -16.692372)
				)
			)
		)
		(zone
			(layer "B.Cu")
			(hatch none 0.5)
			(connect_pads
				(clearance 0)
			)
			(min_thickness 0.25)
			(keepout
				(tracks allowed)
				(vias not_allowed)
				(pads allowed)
				(copperpour not_allowed)
				(footprints allowed)
			)
			(placement
				(enabled no)
				(sheetname "")
			)
			(fill
				(thermal_gap 0.5)
				(thermal_bridge_width 0.5)
				(island_removal_mode 0)
			)
			(polygon
				(pts
					(xy 396.724886 -16.692372) (xy 397.232886 -16.692372) (xy 397.232886 -17.073372) (xy 396.724886 -17.073372)
				)
			)
		)
	)
)
